# T6G (Grand Teton) — schematic netlist excerpt (pin names and nets, part order shuffled) for the footprints in the layout excerpt that follows; sources: Cadence DE-HDL packaged netlist, KiCad conversion of 04192023_DAF0TMB3IC0_F0TG_MB_C_brd_V02_OCP.brd

R183  Q_RES  0 5% CHIP  pkg 0402LF  page 82 : A = CPU0_CORETYPE0 ; B = FM_CPU0_CORETYPE0
R6030  Q_RES  33 5% CHIP  pkg 0402LF  page 80 : A = CLK_GEN2_GPU_FPGA_OE_N ; B = CLK_GEN2_GPU_FPGA_OE_R_N

(kicad_pcb
	(version 20260206)
	(generator "pcbnew")
	(generator_version "10.0")
	(general
		(thickness 1.6)
		(legacy_teardrops no)
	)
	(paper "A4")
	(title_block
		(title "04192023_DAF0TMB3IC0_F0TG_MB_C_brd_V02_OCP.brd")
		(comment 1 "Grand Teton / footprints 1802-1803 of 8354")
	)
	(layers
		(0 "F.Cu" signal "TOP")
		(4 "In1.Cu" signal "GND")
		(6 "In2.Cu" signal "IN1")
		(8 "In3.Cu" signal "GND1")
		(10 "In4.Cu" signal "IN2")
		(12 "In5.Cu" signal "GND2")
		(14 "In6.Cu" signal "IN3")
		(16 "In7.Cu" signal "GND3")
		(18 "In8.Cu" signal "VCC")
		(20 "In9.Cu" signal "VCC1")
		(22 "In10.Cu" signal "GND4")
		(24 "In11.Cu" signal "IN4")
		(26 "In12.Cu" signal "GND5")
		(28 "In13.Cu" signal "IN5")
		(30 "In14.Cu" signal "GND6")
		(32 "In15.Cu" signal "IN6")
		(34 "In16.Cu" signal "GND7")
		(2 "B.Cu" signal "BOTTOM")
		(9 "F.Adhes" user "F.Adhesive")
		(11 "B.Adhes" user "B.Adhesive")
		(13 "F.Paste" user "Package Geometry/Pastemask Top")
		(15 "B.Paste" user "Package Geometry/Pastemask Bottom")
		(5 "F.SilkS" user "Ref Des/Silkscreen Top")
		(7 "B.SilkS" user "Ref Des/Silkscreen Bottom")
		(1 "F.Mask" user "Board Geometry/Soldermask Top")
		(3 "B.Mask" user "Board Geometry/Soldermask Bottom")
		(17 "Dwgs.User" user "User.Drawings")
		(19 "Cmts.User" user "User.Comments")
		(21 "Eco1.User" user "User.Eco1")
		(23 "Eco2.User" user "User.Eco2")
		(25 "Edge.Cuts" user "Board Geometry/Outline")
		(27 "Margin" user)
		(31 "F.CrtYd" user "Package Geometry/Place Bound Top")
		(29 "B.CrtYd" user "Package Geometry/Place Bound Bottom")
		(35 "F.Fab" user "Ref Des/Assembly Top")
		(33 "B.Fab" user "Ref Des/Assembly Bottom")
	)
	(footprint ""
		(layer "F.Cu")
		(at 188.849 -100.294948 90)
		(property "Reference" "R183"
			(at 0 0 90)
			(layer "F.SilkS")
			(hide yes)
			(effects
				(font
					(size 1.27 1.27)
				)
			)
		)
		(property "Value" ""
			(at 0 0 90)
			(layer "F.Fab")
			(effects
				(font
					(size 1.27 1.27)
				)
			)
		)
		(duplicate_pad_numbers_are_jumpers no)
		(fp_line
			(start 0.7874 -0.4064)
			(end 0.7874 0.4064)
			(stroke
				(width 0.1524)
				(type default)
			)
			(layer "F.SilkS")
		)
		(fp_line
			(start -0.7874 -0.4064)
			(end 0.7874 -0.4064)
			(stroke
				(width 0.1524)
				(type default)
			)
			(layer "F.SilkS")
		)
		(fp_line
			(start 0.7874 0.4064)
			(end -0.7874 0.4064)
			(stroke
				(width 0.1524)
				(type default)
			)
			(layer "F.SilkS")
		)
		(fp_line
			(start -0.7874 0.4064)
			(end -0.7874 -0.4064)
			(stroke
				(width 0.1524)
				(type default)
			)
			(layer "F.SilkS")
		)
		(fp_line
			(start -0.12065 -0.305054)
			(end -0.12065 -0.2794)
			(stroke
				(width 0.1)
				(type default)
			)
			(layer "F.Fab")
		)
		(fp_line
			(start -0.67945 -0.305054)
			(end -0.12065 -0.305054)
			(stroke
				(width 0.1)
				(type default)
			)
			(layer "F.Fab")
		)
		(fp_line
			(start 0.67945 -0.3048)
			(end 0.67945 0.3048)
			(stroke
				(width 0.1)
				(type default)
			)
			(layer "F.Fab")
		)
		(fp_line
			(start 0.12065 -0.3048)
			(end 0.67945 -0.3048)
			(stroke
				(width 0.1)
				(type default)
			)
			(layer "F.Fab")
		)
		(fp_line
			(start 0.12065 -0.2794)
			(end 0.12065 -0.3048)
			(stroke
				(width 0.1)
				(type default)
			)
			(layer "F.Fab")
		)
		(fp_line
			(start -0.12065 -0.2794)
			(end 0.12065 -0.2794)
			(stroke
				(width 0.1)
				(type default)
			)
			(layer "F.Fab")
		)
		(fp_line
			(start 0.120396 0.2794)
			(end -0.12065 0.2794)
			(stroke
				(width 0.1)
				(type default)
			)
			(layer "F.Fab")
		)
		(fp_line
			(start -0.12065 0.2794)
			(end -0.12065 0.3048)
			(stroke
				(width 0.1)
				(type default)
			)
			(layer "F.Fab")
		)
		(fp_line
			(start 0.67945 0.3048)
			(end 0.120396 0.3048)
			(stroke
				(width 0.1)
				(type default)
			)
			(layer "F.Fab")
		)
		(fp_line
			(start 0.120396 0.3048)
			(end 0.120396 0.2794)
			(stroke
				(width 0.1)
				(type default)
			)
			(layer "F.Fab")
		)
		(fp_line
			(start -0.12065 0.3048)
			(end -0.67945 0.3048)
			(stroke
				(width 0.1)
				(type default)
			)
			(layer "F.Fab")
		)
		(fp_line
			(start -0.67945 0.3048)
			(end -0.67945 -0.305054)
			(stroke
				(width 0.1)
				(type default)
			)
			(layer "F.Fab")
		)
		(pad "1" smd circle
			(at -0.40005 0 90)
			(size 0 0)
			(layers "F.Cu" "F.Mask" "F.Paste")
			(net "CPU0_CORETYPE0")
		)
		(pad "2" smd circle
			(at 0.40005 0 90)
			(size 0 0)
			(layers "F.Cu" "F.Mask" "F.Paste")
			(net "FM_CPU0_CORETYPE0")
		)
	)
	(footprint ""
		(layer "F.Cu")
		(at 171.196 -122.646948)
		(property "Reference" "R6030"
			(at 0 0 0)
			(layer "F.SilkS")
			(hide yes)
			(effects
				(font
					(size 1.27 1.27)
				)
			)
		)
		(property "Value" ""
			(at 0 0 0)
			(layer "F.Fab")
			(effects
				(font
					(size 1.27 1.27)
				)
			)
		)
		(duplicate_pad_numbers_are_jumpers no)
		(fp_line
			(start -0.7874 -0.4064)
			(end 0.7874 -0.4064)
			(stroke
				(width 0.1524)
				(type default)
			)
			(layer "F.SilkS")
		)
		(fp_line
			(start -0.7874 0.4064)
			(end -0.7874 -0.4064)
			(stroke
				(width 0.1524)
				(type default)
			)
			(layer "F.SilkS")
		)
		(fp_line
			(start 0.7874 -0.4064)
			(end 0.7874 0.4064)
			(stroke
				(width 0.1524)
				(type default)
			)
			(layer "F.SilkS")
		)
		(fp_line
			(start 0.7874 0.4064)
			(end -0.7874 0.4064)
			(stroke
				(width 0.1524)
				(type default)
			)
			(layer "F.SilkS")
		)
		(fp_line
			(start -0.67945 -0.305054)
			(end -0.12065 -0.305054)
			(stroke
				(width 0.1)
				(type default)
			)
			(layer "F.Fab")
		)
		(fp_line
			(start -0.67945 0.3048)
			(end -0.67945 -0.305054)
			(stroke
				(width 0.1)
				(type default)
			)
			(layer "F.Fab")
		)
		(fp_line
			(start -0.12065 -0.305054)
			(end -0.12065 -0.2794)
			(stroke
				(width 0.1)
				(type default)
			)
			(layer "F.Fab")
		)
		(fp_line
			(start -0.12065 -0.2794)
			(end 0.12065 -0.2794)
			(stroke
				(width 0.1)
				(type default)
			)
			(layer "F.Fab")
		)
		(fp_line
			(start -0.12065 0.2794)
			(end -0.12065 0.3048)
			(stroke
				(width 0.1)
				(type default)
			)
			(layer "F.Fab")
		)
		(fp_line
			(start -0.12065 0.3048)
			(end -0.67945 0.3048)
			(stroke
				(width 0.1)
				(type default)
			)
			(layer "F.Fab")
		)
		(fp_line
			(start 0.120396 0.2794)
			(end -0.12065 0.2794)
			(stroke
				(width 0.1)
				(type default)
			)
			(layer "F.Fab")
		)
		(fp_line
			(start 0.120396 0.3048)
			(end 0.120396 0.2794)
			(stroke
				(width 0.1)
				(type default)
			)
			(layer "F.Fab")
		)
		(fp_line
			(start 0.12065 -0.3048)
			(end 0.67945 -0.3048)
			(stroke
				(width 0.1)
				(type default)
			)
			(layer "F.Fab")
		)
		(fp_line
			(start 0.12065 -0.2794)
			(end 0.12065 -0.3048)
			(stroke
				(width 0.1)
				(type default)
			)
			(layer "F.Fab")
		)
		(fp_line
			(start 0.67945 -0.3048)
			(end 0.67945 0.3048)
			(stroke
				(width 0.1)
				(type default)
			)
			(layer "F.Fab")
		)
		(fp_line
			(start 0.67945 0.3048)
			(end 0.120396 0.3048)
			(stroke
				(width 0.1)
				(type default)
			)
			(layer "F.Fab")
		)
		(pad "1" smd circle
			(at -0.40005 0)
			(size 0 0)
			(layers "F.Cu" "F.Mask" "F.Paste")
			(net "CLK_GEN2_GPU_FPGA_OE_N")
		)
		(pad "2" smd circle
			(at 0.40005 0)
			(size 0 0)
			(layers "F.Cu" "F.Mask" "F.Paste")
			(net "CLK_GEN2_GPU_FPGA_OE_R_N")
		)
	)
)
